(kicad_pcb
	(version 20240108)
	(generator "pcbnew")
	(generator_version "8.0")
	(general
		(thickness 1.62)
		(legacy_teardrops no)
	)
	(paper "A4")
	(title_block
		(title "Jetson Orin Baseboard")
		(date "2025-03-12")
		(rev "1.3.4")
		(company "Antmicro Ltd")
		(comment 1 "www.antmicro.com")
		(comment 9 "footprints 614-614 of 677")
	)
	(layers
		(0 "F.Cu" signal)
		(1 "In1.Cu" signal)
		(2 "In2.Cu" signal)
		(3 "In3.Cu" signal)
		(4 "In4.Cu" jumper)
		(5 "In5.Cu" signal)
		(6 "In6.Cu" signal)
		(31 "B.Cu" signal)
		(32 "B.Adhes" user "B.Adhesive")
		(33 "F.Adhes" user "F.Adhesive")
		(34 "B.Paste" user)
		(35 "F.Paste" user)
		(36 "B.SilkS" user "B.Silkscreen")
		(37 "F.SilkS" user "F.Silkscreen")
		(38 "B.Mask" user)
		(39 "F.Mask" user)
		(40 "Dwgs.User" user "User.Drawings")
		(41 "Cmts.User" user "User.Comments")
		(42 "Eco1.User" user "User.Eco1")
		(43 "Eco2.User" user "User.Eco2")
		(44 "Edge.Cuts" user)
		(45 "Margin" user)
		(46 "B.CrtYd" user "B.Courtyard")
		(47 "F.CrtYd" user "F.Courtyard")
		(48 "B.Fab" user)
		(49 "F.Fab" user)
	)
	(footprint "antmicro-footprints:Bus_M.2_Socket_Key_M_TE_1-2199230-6"
		(layer "B.Cu")
		(at 120.591 86.751 90)
		(property "Reference" "J2"
			(at -10.649 5.259 180)
			(layer "B.SilkS")
			(effects
				(font
					(size 0.7 0.7)
					(thickness 0.15)
				)
				(justify right bottom mirror)
			)
		)
		(property "Value" "Bus_M.2_1-2199230-6"
			(at -11.25 -6.124 90)
			(layer "B.Fab")
			(effects
				(font
					(size 0.7 0.7)
					(thickness 0.15)
				)
				(justify right bottom mirror)
			)
		)
		(property "Footprint" "antmicro-footprints:Bus_M.2_Socket_Key_M_TE_1-2199230-6"
			(at 0 0 90)
			(layer "F.Fab")
			(hide yes)
			(effects
				(font
					(size 1.27 1.27)
					(thickness 0.15)
				)
			)
		)
		(property "Datasheet" "https://www.te.com/commerce/DocumentDelivery/DDEController?Action=srchrtrv&DocNm=2199230&DocType=Customer+Drawing&DocLang=English"
			(at 0 0 90)
			(layer "F.Fab")
			(hide yes)
			(effects
				(font
					(size 1.27 1.27)
					(thickness 0.15)
				)
			)
		)
		(property "Author" "Antmicro"
			(at 207.342 -33.84 0)
			(layer "B.Fab")
			(hide yes)
			(effects
				(font
					(size 1 1)
					(thickness 0.15)
				)
				(justify mirror)
			)
		)
		(property "License" "Apache-2.0"
			(at 207.342 -33.84 0)
			(layer "B.Fab")
			(hide yes)
			(effects
				(font
					(size 1 1)
					(thickness 0.15)
				)
				(justify mirror)
			)
		)
		(property "MPN" "1-2199230-6"
			(at 207.342 -33.84 0)
			(layer "B.Fab")
			(hide yes)
			(effects
				(font
					(size 1 1)
					(thickness 0.15)
				)
				(justify mirror)
			)
		)
		(property "Manufacturer" "TE Connectivity"
			(at 207.342 -33.84 0)
			(layer "B.Fab")
			(hide yes)
			(effects
				(font
					(size 1 1)
					(thickness 0.15)
				)
				(justify mirror)
			)
		)
		(sheetname "M.2")
		(sheetfile "m-2.kicad_sch")
		(attr smd)
		(fp_line
			(start 10.948 -3.999)
			(end 9.448 -3.999)
			(stroke
				(width 0.15)
				(type solid)
			)
			(layer "B.SilkS")
		)
		(fp_line
			(start 7.148 -3.999)
			(end 5.347 -3.999)
			(stroke
				(width 0.15)
				(type solid)
			)
			(layer "B.SilkS")
		)
		(fp_line
			(start -9.352 -3.999)
			(end -10.951 -3.999)
			(stroke
				(width 0.15)
				(type solid)
			)
			(layer "B.SilkS")
		)
		(fp_line
			(start -10.951 -3.999)
			(end -10.951 -2.7)
			(stroke
				(width 0.15)
				(type solid)
			)
			(layer "B.SilkS")
		)
		(fp_line
			(start 10.948 -2.3)
			(end 10.948 -3.999)
			(stroke
				(width 0.15)
				(type solid)
			)
			(layer "B.SilkS")
		)
		(fp_line
			(start -10.951 -0.55)
			(end -10.951 1.401)
			(stroke
				(width 0.15)
				(type solid)
			)
			(layer "B.SilkS")
		)
		(fp_line
			(start 10.948 1.301)
			(end 10.948 -0.449)
			(stroke
				(width 0.15)
				(type solid)
			)
			(layer "B.SilkS")
		)
		(fp_line
			(start 6.898 3.75)
			(end 5.097 3.75)
			(stroke
				(width 0.15)
				(type solid)
			)
			(layer "B.SilkS")
		)
		(fp_circle
			(center -9.25 4.875)
			(end -9.201 4.826)
			(stroke
				(width 0.15)
				(type solid)
			)
			(fill solid)
			(layer "B.SilkS")
		)
		(fp_circle
			(center -9.25 5.651)
			(end -9.2 5.651)
			(stroke
				(width 0.15)
				(type solid)
			)
			(fill solid)
			(layer "B.SilkS")
		)
		(fp_line
			(start 11.15 -4.78)
			(end -11.16 -4.78)
			(stroke
				(width 0.05)
				(type solid)
			)
			(layer "B.CrtYd")
		)
		(fp_line
			(start -11.16 -4.78)
			(end -11.16 4.83)
			(stroke
				(width 0.05)
				(type solid)
			)
			(layer "B.CrtYd")
		)
		(fp_line
			(start 11.15 4.83)
			(end 11.15 -4.78)
			(stroke
				(width 0.05)
				(type solid)
			)
			(layer "B.CrtYd")
		)
		(fp_line
			(start -11.16 4.83)
			(end 11.15 4.83)
			(stroke
				(width 0.05)
				(type solid)
			)
			(layer "B.CrtYd")
		)
		(fp_line
			(start 10.95 -4.2)
			(end 10.95 4.1)
			(stroke
				(width 0.15)
				(type solid)
			)
			(layer "B.Fab")
		)
		(fp_line
			(start -10.949 -4.2)
			(end 10.95 -4.2)
			(stroke
				(width 0.15)
				(type solid)
			)
			(layer "B.Fab")
		)
		(fp_line
			(start -10.949 3.55)
			(end -10.949 -4.2)
			(stroke
				(width 0.15)
				(type solid)
			)
			(layer "B.Fab")
		)
		(fp_line
			(start 10.95 4.1)
			(end -10.4 4.1)
			(stroke
				(width 0.15)
				(type solid)
			)
			(layer "B.Fab")
		)
		(fp_line
			(start -10.4 4.1)
			(end -10.949 3.55)
			(stroke
				(width 0.15)
				(type solid)
			)
			(layer "B.Fab")
		)
		(fp_text user "${REFERENCE}"
			(at -11.35 -8.124 90)
			(layer "B.Fab")
			(hide yes)
			(effects
				(font
					(size 0.7 0.7)
					(thickness 0.15)
				)
				(justify right bottom mirror)
			)
		)
		(fp_text user "License: Apache-2.0"
			(at -11.35 -10.525 90)
			(layer "B.Fab")
			(hide yes)
			(effects
				(font
					(size 0.7 0.7)
					(thickness 0.15)
				)
				(justify right bottom mirror)
			)
		)
		(fp_text user "Author: Antmicro"
			(at -11.35 -9.325 90)
			(layer "B.Fab")
			(hide yes)
			(effects
				(font
					(size 0.7 0.7)
					(thickness 0.15)
				)
				(justify right bottom mirror)
			)
		)
		(pad "" np_thru_hole circle
			(at -10 -1.499 90)
			(size 1.1 1.1)
			(drill 1.1)
			(layers "*.Mask")
		)
		(pad "" np_thru_hole circle
			(at 9.997 -1.499 90)
			(size 1.6 1.6)
			(drill 1.6)
			(layers "*.Mask")
		)
		(pad "1" smd rect
			(at -9.25 3.775 90)
			(size 0.3 1.55)
			(layers "B.Cu" "B.Paste" "B.Mask")
			(net 1 "GND")
			(pinfunction "GND")
			(pintype "power_in")
		)
		(pad "2" smd rect
			(at -9.003 -3.773 90)
			(size 0.3 1.55)
			(layers "B.Cu" "B.Paste" "B.Mask")
			(net 635 "/M.2/3V3_M2")
			(pinfunction "3V3")
			(pintype "passive")
		)
		(pad "3" smd rect
			(at -8.753 3.775 90)
			(size 0.3 1.55)
			(layers "B.Cu" "B.Paste" "B.Mask")
			(net 1 "GND")
			(pinfunction "GND")
			(pintype "passive")
		)
		(pad "4" smd rect
			(at -8.503 -3.773 90)
			(size 0.3 1.55)
			(layers "B.Cu" "B.Paste" "B.Mask")
			(net 635 "/M.2/3V3_M2")
			(pinfunction "3V3")
			(pintype "passive")
		)
		(pad "5" smd rect
			(at -8.253 3.775 90)
			(size 0.3 1.55)
			(layers "B.Cu" "B.Paste" "B.Mask")
			(net 53 "PCIE0_RX3_N")
			(pinfunction "PER3_N")
			(pintype "output")
		)
		(pad "6" smd rect
			(at -8.001 -3.773 90)
			(size 0.3 1.55)
			(layers "B.Cu" "B.Paste" "B.Mask")
			(net 332 "unconnected-(J2-NC-Pad6)")
			(pinfunction "NC")
			(pintype "no_connect")
		)
		(pad "7" smd rect
			(at -7.752 3.775 90)
			(size 0.3 1.55)
			(layers "B.Cu" "B.Paste" "B.Mask")
			(net 54 "PCIE0_RX3_P")
			(pinfunction "PER3_P")
			(pintype "output")
		)
		(pad "8" smd rect
			(at -7.502 -3.773 90)
			(size 0.3 1.55)
			(layers "B.Cu" "B.Paste" "B.Mask")
			(net 341 "unconnected-(J2-NC-Pad8)")
			(pinfunction "NC")
			(pintype "no_connect")
		)
		(pad "9" smd rect
			(at -7.252 3.775 90)
			(size 0.3 1.55)
			(layers "B.Cu" "B.Paste" "B.Mask")
			(net 1 "GND")
			(pinfunction "GND")
			(pintype "passive")
		)
		(pad "10" smd rect
			(at -7.002 -3.773 90)
			(size 0.3 1.55)
			(layers "B.Cu" "B.Paste" "B.Mask")
			(net 140 "Net-(D1-C)")
			(pinfunction "LED")
			(pintype "passive")
		)
		(pad "11" smd rect
			(at -6.752 3.775 90)
			(size 0.3 1.55)
			(layers "B.Cu" "B.Paste" "B.Mask")
			(net 95 "/M.2/C_PCIE0_TX3_N")
			(pinfunction "PET3_N")
			(pintype "input")
		)
		(pad "12" smd rect
			(at -6.502 -3.773 90)
			(size 0.3 1.55)
			(layers "B.Cu" "B.Paste" "B.Mask")
			(net 635 "/M.2/3V3_M2")
			(pinfunction "3V3")
			(pintype "passive")
		)
		(pad "13" smd rect
			(at -6.252 3.775 90)
			(size 0.3 1.55)
			(layers "B.Cu" "B.Paste" "B.Mask")
			(net 94 "/M.2/C_PCIE0_TX3_P")
			(pinfunction "PET3_P")
			(pintype "input")
		)
		(pad "14" smd rect
			(at -6.002 -3.773 90)
			(size 0.3 1.55)
			(layers "B.Cu" "B.Paste" "B.Mask")
			(net 635 "/M.2/3V3_M2")
			(pinfunction "3V3")
			(pintype "passive")
		)
		(pad "15" smd rect
			(at -5.752 3.775 90)
			(size 0.3 1.55)
			(layers "B.Cu" "B.Paste" "B.Mask")
			(net 1 "GND")
			(pinfunction "GND")
			(pintype "passive")
		)
		(pad "16" smd rect
			(at -5.502 -3.773 90)
			(size 0.3 1.55)
			(layers "B.Cu" "B.Paste" "B.Mask")
			(net 635 "/M.2/3V3_M2")
			(pinfunction "3V3")
			(pintype "passive")
		)
		(pad "17" smd rect
			(at -5.252 3.775 90)
			(size 0.3 1.55)
			(layers "B.Cu" "B.Paste" "B.Mask")
			(net 51 "PCIE0_RX2_N")
			(pinfunction "PER2_N")
			(pintype "output")
		)
		(pad "18" smd rect
			(at -5.002 -3.773 90)
			(size 0.3 1.55)
			(layers "B.Cu" "B.Paste" "B.Mask")
			(net 635 "/M.2/3V3_M2")
			(pinfunction "3V3")
			(pintype "passive")
		)
		(pad "19" smd rect
			(at -4.752 3.775 90)
			(size 0.3 1.55)
			(layers "B.Cu" "B.Paste" "B.Mask")
			(net 52 "PCIE0_RX2_P")
			(pinfunction "PER2_P")
			(pintype "output")
		)
		(pad "20" smd rect
			(at -4.502 -3.773 90)
			(size 0.3 1.55)
			(layers "B.Cu" "B.Paste" "B.Mask")
			(net 359 "unconnected-(J2-NC-Pad20)")
			(pinfunction "NC")
			(pintype "no_connect")
		)
		(pad "21" smd rect
			(at -4.252 3.775 90)
			(size 0.3 1.55)
			(layers "B.Cu" "B.Paste" "B.Mask")
			(net 1 "GND")
			(pinfunction "GND")
			(pintype "passive")
		)
		(pad "22" smd rect
			(at -4.002 -3.773 90)
			(size 0.3 1.55)
			(layers "B.Cu" "B.Paste" "B.Mask")
			(net 431 "unconnected-(J2-NC-Pad22)")
			(pinfunction "NC")
			(pintype "no_connect")
		)
		(pad "23" smd rect
			(at -3.751 3.775 90)
			(size 0.3 1.55)
			(layers "B.Cu" "B.Paste" "B.Mask")
			(net 93 "/M.2/C_PCIE0_TX2_N")
			(pinfunction "PET2_N")
			(pintype "input")
		)
		(pad "24" smd rect
			(at -3.501 -3.773 90)
			(size 0.3 1.55)
			(layers "B.Cu" "B.Paste" "B.Mask")
			(net 432 "unconnected-(J2-NC-Pad24)")
			(pinfunction "NC")
			(pintype "no_connect")
		)
		(pad "25" smd rect
			(at -3.251 3.775 90)
			(size 0.3 1.55)
			(layers "B.Cu" "B.Paste" "B.Mask")
			(net 92 "/M.2/C_PCIE0_TX2_P")
			(pinfunction "PET2_P")
			(pintype "input")
		)
		(pad "26" smd rect
			(at -3.001 -3.773 90)
			(size 0.3 1.55)
			(layers "B.Cu" "B.Paste" "B.Mask")
			(net 435 "unconnected-(J2-NC-Pad26)")
			(pinfunction "NC")
			(pintype "no_connect")
		)
		(pad "27" smd rect
			(at -2.751 3.775 90)
			(size 0.3 1.55)
			(layers "B.Cu" "B.Paste" "B.Mask")
			(net 1 "GND")
			(pinfunction "GND")
			(pintype "passive")
		)
		(pad "28" smd rect
			(at -2.501 -3.773 90)
			(size 0.3 1.55)
			(layers "B.Cu" "B.Paste" "B.Mask")
			(net 458 "unconnected-(J2-NC-Pad28)")
			(pinfunction "NC")
			(pintype "no_connect")
		)
		(pad "29" smd rect
			(at -2.251 3.775 90)
			(size 0.3 1.55)
			(layers "B.Cu" "B.Paste" "B.Mask")
			(net 49 "PCIE0_RX1_N")
			(pinfunction "PER1_N")
			(pintype "output")
		)
		(pad "30" smd rect
			(at -2.001 -3.773 90)
			(size 0.3 1.55)
			(layers "B.Cu" "B.Paste" "B.Mask")
			(net 462 "unconnected-(J2-NC-Pad30)")
			(pinfunction "NC")
			(pintype "no_connect")
		)
		(pad "31" smd rect
			(at -1.752 3.775 90)
			(size 0.3 1.55)
			(layers "B.Cu" "B.Paste" "B.Mask")
			(net 50 "PCIE0_RX1_P")
			(pinfunction "PER1_P")
			(pintype "output")
		)
		(pad "32" smd rect
			(at -1.502 -3.773 90)
			(size 0.3 1.55)
			(layers "B.Cu" "B.Paste" "B.Mask")
			(net 464 "unconnected-(J2-NC-Pad32)")
			(pinfunction "NC")
			(pintype "no_connect")
		)
		(pad "33" smd rect
			(at -1.252 3.775 90)
			(size 0.3 1.55)
			(layers "B.Cu" "B.Paste" "B.Mask")
			(net 1 "GND")
			(pinfunction "GND")
			(pintype "passive")
		)
		(pad "34" smd rect
			(at -1.002 -3.773 90)
			(size 0.3 1.55)
			(layers "B.Cu" "B.Paste" "B.Mask")
			(net 466 "unconnected-(J2-NC-Pad34)")
			(pinfunction "NC")
			(pintype "no_connect")
		)
		(pad "35" smd rect
			(at -0.751 3.775 90)
			(size 0.3 1.55)
			(layers "B.Cu" "B.Paste" "B.Mask")
			(net 91 "/M.2/C_PCIE0_TX1_N")
			(pinfunction "PET1_N")
			(pintype "input")
		)
		(pad "36" smd rect
			(at -0.501 -3.773 90)
			(size 0.3 1.55)
			(layers "B.Cu" "B.Paste" "B.Mask")
			(net 503 "unconnected-(J2-NC-Pad36)")
			(pinfunction "NC")
			(pintype "no_connect")
		)
		(pad "37" smd rect
			(at -0.251 3.775 90)
			(size 0.3 1.55)
			(layers "B.Cu" "B.Paste" "B.Mask")
			(net 90 "/M.2/C_PCIE0_TX1_P")
			(pinfunction "PET1_P")
			(pintype "input")
		)
		(pad "38" smd rect
			(at -0.001 -3.773 90)
			(size 0.3 1.55)
			(layers "B.Cu" "B.Paste" "B.Mask")
			(net 504 "unconnected-(J2-NC-Pad38)")
			(pinfunction "NC")
			(pintype "no_connect")
		)
		(pad "39" smd rect
			(at 0.248 3.775 90)
			(size 0.3 1.55)
			(layers "B.Cu" "B.Paste" "B.Mask")
			(net 1 "GND")
			(pinfunction "GND")
			(pintype "passive")
		)
		(pad "40" smd rect
			(at 0.498 -3.773 90)
			(size 0.3 1.55)
			(layers "B.Cu" "B.Paste" "B.Mask")
			(net 244 "/M.2/M2_M_SMB_CLK")
			(pinfunction "SMB_CLK")
			(pintype "input")
		)
		(pad "41" smd rect
			(at 0.748 3.775 90)
			(size 0.3 1.55)
			(layers "B.Cu" "B.Paste" "B.Mask")
			(net 47 "PCIE0_RX0_N")
			(pinfunction "PER0_N")
			(pintype "output")
		)
		(pad "42" smd rect
			(at 0.998 -3.773 90)
			(size 0.3 1.55)
			(layers "B.Cu" "B.Paste" "B.Mask")
			(net 245 "/M.2/M2_M_SMB_DATA")
			(pinfunction "SMB_DATA")
			(pintype "bidirectional")
		)
		(pad "43" smd rect
			(at 1.249 3.775 90)
			(size 0.3 1.55)
			(layers "B.Cu" "B.Paste" "B.Mask")
			(net 48 "PCIE0_RX0_P")
			(pinfunction "PER0_P")
			(pintype "output")
		)
		(pad "44" smd rect
			(at 1.499 -3.773 90)
			(size 0.3 1.55)
			(layers "B.Cu" "B.Paste" "B.Mask")
			(net 246 "/M.2/~{M2_M_ALERT}")
			(pinfunction "ALERT")
			(pintype "output")
		)
		(pad "45" smd rect
			(at 1.749 3.775 90)
			(size 0.3 1.55)
			(layers "B.Cu" "B.Paste" "B.Mask")
			(net 1 "GND")
			(pinfunction "GND")
			(pintype "passive")
		)
		(pad "46" smd rect
			(at 1.999 -3.773 90)
			(size 0.3 1.55)
			(layers "B.Cu" "B.Paste" "B.Mask")
			(net 506 "unconnected-(J2-NC-Pad46)")
			(pinfunction "NC")
			(pintype "no_connect")
		)
		(pad "47" smd rect
			(at 2.249 3.775 90)
			(size 0.3 1.55)
			(layers "B.Cu" "B.Paste" "B.Mask")
			(net 89 "/M.2/C_PCIE0_TX0_N")
			(pinfunction "PET0_N")
			(pintype "input")
		)
		(pad "48" smd rect
			(at 2.499 -3.773 90)
			(size 0.3 1.55)
			(layers "B.Cu" "B.Paste" "B.Mask")
			(net 507 "unconnected-(J2-NC-Pad48)")
			(pinfunction "NC")
			(pintype "no_connect")
		)
		(pad "49" smd rect
			(at 2.749 3.775 90)
			(size 0.3 1.55)
			(layers "B.Cu" "B.Paste" "B.Mask")
			(net 88 "/M.2/C_PCIE0_TX0_P")
			(pinfunction "PET0_P")
			(pintype "input")
		)
		(pad "50" smd rect
			(at 2.999 -3.773 90)
			(size 0.3 1.55)
			(layers "B.Cu" "B.Paste" "B.Mask")
			(net 247 "/M.2/~{M2_M_PERST}")
			(pinfunction "~{PERST}")
			(pintype "input")
		)
		(pad "51" smd rect
			(at 3.249 3.775 90)
			(size 0.3 1.55)
			(layers "B.Cu" "B.Paste" "B.Mask")
			(net 1 "GND")
			(pinfunction "GND")
			(pintype "passive")
		)
		(pad "52" smd rect
			(at 3.499 -3.773 90)
			(size 0.3 1.55)
			(layers "B.Cu" "B.Paste" "B.Mask")
			(net 248 "/M.2/~{M2_M_CLKREQ0}")
			(pinfunction "~{CLKREQ}")
			(pintype "output")
		)
		(pad "53" smd rect
			(at 3.749 3.775 90)
			(size 0.3 1.55)
			(layers "B.Cu" "B.Paste" "B.Mask")
			(net 55 "PCIE0_CLK_N")
			(pinfunction "REFCLK_N")
			(pintype "input")
		)
		(pad "54" smd rect
			(at 3.999 -3.773 90)
			(size 0.3 1.55)
			(layers "B.Cu" "B.Paste" "B.Mask")
			(net 249 "/M.2/~{M2_M_PEWAKE0}")
			(pinfunction "~{PEWAKE}")
			(pintype "input")
		)
		(pad "55" smd rect
			(at 4.248 3.775 90)
			(size 0.3 1.55)
			(layers "B.Cu" "B.Paste" "B.Mask")
			(net 57 "PCIE0_CLK_P")
			(pinfunction "REFCLK_P")
			(pintype "input")
		)
		(pad "56" smd rect
			(at 4.498 -3.773 90)
			(size 0.3 1.55)
			(layers "B.Cu" "B.Paste" "B.Mask")
			(net 509 "unconnected-(J2-NC-Pad56)")
			(pinfunction "NC")
			(pintype "no_connect")
		)
		(pad "57" smd rect
			(at 4.748 3.775 90)
			(size 0.3 1.55)
			(layers "B.Cu" "B.Paste" "B.Mask")
			(net 1 "GND")
			(pinfunction "GND")
			(pintype "passive")
		)
		(pad "58" smd rect
			(at 4.998 -3.773 90)
			(size 0.3 1.55)
			(layers "B.Cu" "B.Paste" "B.Mask")
			(net 510 "unconnected-(J2-NC-Pad58)")
			(pinfunction "NC")
			(pintype "no_connect")
		)
		(pad "67" smd rect
			(at 7.248 3.775 90)
			(size 0.3 1.55)
			(layers "B.Cu" "B.Paste" "B.Mask")
			(net 531 "unconnected-(J2-NC-Pad67)")
			(pinfunction "NC")
			(pintype "no_connect")
		)
		(pad "68" smd rect
			(at 7.498 -3.773 90)
			(size 0.3 1.55)
			(layers "B.Cu" "B.Paste" "B.Mask")
			(net 250 "/M.2/M2_M_SUSCLK")
			(pinfunction "SUSCLK")
			(pintype "input")
		)
		(pad "69" smd rect
			(at 7.748 3.775 90)
			(size 0.3 1.55)
			(layers "B.Cu" "B.Paste" "B.Mask")
			(net 532 "unconnected-(J2-NC-Pad69)")
			(pinfunction "NC")
			(pintype "no_connect")
		)
		(pad "70" smd rect
			(at 7.998 -3.773 90)
			(size 0.3 1.55)
			(layers "B.Cu" "B.Paste" "B.Mask")
			(net 635 "/M.2/3V3_M2")
			(pinfunction "3V3")
			(pintype "passive")
		)
		(pad "71" smd rect
			(at 8.247 3.775 90)
			(size 0.3 1.55)
			(layers "B.Cu" "B.Paste" "B.Mask")
			(net 1 "GND")
			(pinfunction "GND")
			(pintype "passive")
		)
		(pad "72" smd rect
			(at 8.497 -3.773 90)
			(size 0.3 1.55)
			(layers "B.Cu" "B.Paste" "B.Mask")
			(net 635 "/M.2/3V3_M2")
			(pinfunction "3V3")
			(pintype "passive")
		)
		(pad "73" smd rect
			(at 8.747 3.775 90)
			(size 0.3 1.55)
			(layers "B.Cu" "B.Paste" "B.Mask")
			(net 1 "GND")
			(pinfunction "GND")
			(pintype "passive")
		)
		(pad "74" smd rect
			(at 8.997 -3.773 90)
			(size 0.3 1.55)
			(layers "B.Cu" "B.Paste" "B.Mask")
			(net 635 "/M.2/3V3_M2")
			(pinfunction "3V3")
			(pintype "passive")
		)
		(pad "75" smd rect
			(at 9.247 3.775 90)
			(size 0.3 1.55)
			(layers "B.Cu" "B.Paste" "B.Mask")
			(net 1 "GND")
			(pinfunction "GND")
			(pintype "passive")
		)
		(pad "MP1" smd rect
			(at -10.352 3 90)
			(size 1.2 2.75)
			(layers "B.Cu" "B.Paste" "B.Mask")
			(net 1 "GND")
			(pinfunction "MP")
			(pintype "passive")
		)
		(pad "MP2" smd rect
			(at 10.349 3 90)
			(size 1.2 2.75)
			(layers "B.Cu" "B.Paste" "B.Mask")
			(net 1 "GND")
			(pinfunction "MP")
			(pintype "passive")
		)
	)
)
